# T6G (Grand Teton) — schematic netlist excerpt (pin names and nets, part order shuffled) for the footprints in the layout excerpt that follows; sources: Cadence DE-HDL packaged netlist, KiCad conversion of 04192023_DAF0TMB3IC0_F0TG_MB_C_brd_V02_OCP.brd

J69  SCONN288_DDR506112002KQ  IO  pkg DDR288S_1-1VXC  page 93
  VIN_BULK0  = P12V_MEM_CPU0
  RFU0  = NC
  VIN_MGMT  = P3V3_AUX
  HSCL  = I3C_SPD_DDRH_CPU0_SCL
  HSDA  = I3C_SPD_DDRH_CPU0_SDA
  VSS0  = GND
  DQ0_A  = M_H_CPU0_SA_DQ<0>
  VSS1  = GND
  DQ1_A  = M_H_CPU0_SA_DQ<1>
  VSS2  = GND
  DQS0_A_T  = M_H_CPU0_SA_DQS_DP<0>
  DQS0_A_C  = M_H_CPU0_SA_DQS_DN<0>
  VSS3  = GND
  DQ4_A  = M_H_CPU0_SA_DQ<4>
  VSS4  = GND
  DQ5_A  = M_H_CPU0_SA_DQ<5>
  VSS5  = GND
  DQ8_A  = M_H_CPU0_SA_DQ<8>
  VSS6  = GND
  DQ9_A  = M_H_CPU0_SA_DQ<9>
  VSS7  = GND
  DQS1_A_T  = M_H_CPU0_SA_DQS_DP<1>
  DQS1_A_C  = M_H_CPU0_SA_DQS_DN<1>
  VSS8  = GND
  DQ12_A  = M_H_CPU0_SA_DQ<12>
  VSS9  = GND
  DQ13_A  = M_H_CPU0_SA_DQ<13>
  VSS10  = GND
  DQ16_A  = M_H_CPU0_SA_DQ<16>
  VSS11  = GND
  DQ17_A  = M_H_CPU0_SA_DQ<17>
  VSS12  = GND
  DQS2_A_T  = M_H_CPU0_SA_DQS_DP<2>
  DQS2_A_C  = M_H_CPU0_SA_DQS_DN<2>
  VSS13  = GND
  DQ20_A  = M_H_CPU0_SA_DQ<20>
  VSS14  = GND
  DQ21_A  = M_H_CPU0_SA_DQ<21>
  VSS15  = GND
  DQ24_A  = M_H_CPU0_SA_DQ<24>
  VSS16  = GND
  DQ25_A  = M_H_CPU0_SA_DQ<25>
  VSS17  = GND
  DQS3_A_T  = M_H_CPU0_SA_DQS_DP<3>
  DQS3_A_C  = M_H_CPU0_SA_DQS_DN<3>
  VSS18  = GND
  DQ28_A  = M_H_CPU0_SA_DQ<28>
  VSS19  = GND
  DQ29_A  = M_H_CPU0_SA_DQ<29>
  VSS20  = GND
  CB0_A  = M_H_CPU0_SA_CB<0>
  VSS21  = GND
  CB1_A  = M_H_CPU0_SA_CB<1>
  VSS22  = GND
  DQS4_A_T  = M_H_CPU0_SA_DQS_DP<4>
  DQS4_A_C  = M_H_CPU0_SA_DQS_DN<4>
  VSS23  = GND
  CB4_A  = M_H_CPU0_SA_CB<4>
  VSS24  = GND
  CB5_A  = M_H_CPU0_SA_CB<5>
  VSS25  = GND
  ALERT_N  = M_H_CPU0_ALERT_N
  VSS26  = GND
  CS0_A_N  = M_H_CPU0_SA_CS_N<0>
  VSS27  = GND
  CA0_A  = M_H_CPU0_SA_CA<0>
  VSS28  = GND
  CA2_A  = M_H_CPU0_SA_CA<2>
  VSS29  = GND
  CA4_A  = M_H_CPU0_SA_CA<4>
  VSS30  = GND
  CA6_A  = M_H_CPU0_SA_CA<6>
  VSS31  = GND
  PAR_A  = M_H_CPU0_SA_PAR
  VSS32  = GND
  CA0_B  = M_H_CPU0_SB_CA<0>
  VSS33  = GND
  CA2_B  = M_H_CPU0_SB_CA<2>
  VSS34  = GND
  CA4_B  = M_H_CPU0_SB_CA<4>
  VSS35  = GND
  CA6_B  = M_H_CPU0_SB_CA<6>
  VSS36  = GND
  CS0_B_N  = M_H_CPU0_SB_CS_N<0>
  VSS37  = GND
  \lbd||rsp_a_n\  = M_H_CPU0_SA_RSP<0>
  \lbs||rsp_b_n\  = M_H_CPU0_SB_RSP<0>
  VSS38  = GND
  CB4_B  = M_H_CPU0_SB_CB<4>
  VSS39  = GND
  CB5_B  = M_H_CPU0_SB_CB<5>
  VSS40  = GND
  \dqs9_b_t||tdqs9_b_t||dbi4_b_n\  = M_H_CPU0_SB_DQS_DP<9>
  \dqs9_b_c||tdqs9_b_c\  = M_H_CPU0_SB_DQS_DN<9>
  VSS41  = GND
  CB0_B  = M_H_CPU0_SB_CB<0>
  VSS42  = GND
  CB1_B  = M_H_CPU0_SB_CB<1>
  VSS43  = GND
  DQ0_B  = M_H_CPU0_SB_DQ<0>
  VSS44  = GND
  DQ1_B  = M_H_CPU0_SB_DQ<1>
  VSS45  = GND
  DQS0_B_T  = M_H_CPU0_SB_DQS_DP<0>
  DQS0_B_C  = M_H_CPU0_SB_DQS_DN<0>
  VSS46  = GND
  DQ4_B  = M_H_CPU0_SB_DQ<4>
  VSS47  = GND
  DQ5_B  = M_H_CPU0_SB_DQ<5>
  VSS48  = GND
  DQ8_B  = M_H_CPU0_SB_DQ<8>
  VSS49  = GND
  DQ9_B  = M_H_CPU0_SB_DQ<9>
  VSS50  = GND
  DQS1_B_T  = M_H_CPU0_SB_DQS_DP<1>
  DQS1_B_C  = M_H_CPU0_SB_DQS_DN<1>
  VSS51  = GND
  DQ12_B  = M_H_CPU0_SB_DQ<12>
  VSS52  = GND
  DQ13_B  = M_H_CPU0_SB_DQ<13>
  VSS53  = GND
  DQ16_B  = M_H_CPU0_SB_DQ<16>
  VSS54  = GND
  DQ17_B  = M_H_CPU0_SB_DQ<17>
  VSS55  = GND
  DQS2_B_T  = M_H_CPU0_SB_DQS_DP<2>
  DQS2_B_C  = M_H_CPU0_SB_DQS_DN<2>
  VSS56  = GND
  DQ20_B  = M_H_CPU0_SB_DQ<20>
  VSS57  = GND
  DQ21_B  = M_H_CPU0_SB_DQ<21>
  VSS58  = GND
  DQ24_B  = M_H_CPU0_SB_DQ<24>
  VSS59  = GND
  DQ25_B  = M_H_CPU0_SB_DQ<25>
  VSS60  = GND
  DQS3_B_T  = M_H_CPU0_SB_DQS_DP<3>
  DQS3_B_C  = M_H_CPU0_SB_DQS_DN<3>
  VSS61  = GND
  DQ28_B  = M_H_CPU0_SB_DQ<28>
  VSS62  = GND
  DQ29_B  = M_H_CPU0_SB_DQ<29>
  VSS63  = GND
  RFU1  = NC
  VIN_BULK1  = P12V_MEM_CPU0
  VIN_BULK2  = P12V_MEM_CPU0
  \pwr_good||fail_n\  = PWRGD_CHH_CPU0_DIMM
  HAS  = PD_CHH_CPU0_DIMM_SAA
  RFU2  = NC
  RFU3  = NC
  VSS64  = GND
  DQ2_A  = M_H_CPU0_SA_DQ<2>
  VSS65  = GND
  DQ3_A  = M_H_CPU0_SA_DQ<3>
  VSS66  = GND
  \dqs5_a_c||tdqs5_a_c||dqs5_a_t||tdqs5_a_t\  = M_H_CPU0_SA_DQS_DN<5>
  \dqs5_a_t||tdqs5_a_t\  = M_H_CPU0_SA_DQS_DP<5>
  VSS67  = GND
  DQ6_A  = M_H_CPU0_SA_DQ<6>
  VSS68  = GND
  DQ7_A  = M_H_CPU0_SA_DQ<7>
  VSS69  = GND
  DQ10_A  = M_H_CPU0_SA_DQ<10>
  VSS70  = GND
  DQ11_A  = M_H_CPU0_SA_DQ<11>
  VSS71  = GND
  \dqs6_a_c||tdqs6_a_c||dqs6_a_t||tdqs6_a_t\  = M_H_CPU0_SA_DQS_DN<6>
  \dqs6_a_t||tdqs6_a_t\  = M_H_CPU0_SA_DQS_DP<6>
  VSS72  = GND
  DQ14_A  = M_H_CPU0_SA_DQ<14>
  VSS73  = GND
  DQ15_A  = M_H_CPU0_SA_DQ<15>
  VSS74  = GND
  DQ18_A  = M_H_CPU0_SA_DQ<18>
  VSS75  = GND
  DQ19_A  = M_H_CPU0_SA_DQ<19>
  VSS76  = GND
  \dqs7_a_c||tdqs7_a_c\  = M_H_CPU0_SA_DQS_DN<7>
  \dqs7_a_t||tdqs7_a_t\  = M_H_CPU0_SA_DQS_DP<7>
  VSS77  = GND
  DQ22_A  = M_H_CPU0_SA_DQ<22>
  VSS78  = GND
  DQ23_A  = M_H_CPU0_SA_DQ<23>
  VSS79  = GND
  DQ26_A  = M_H_CPU0_SA_DQ<26>
  VSS80  = GND
  DQ27_A  = M_H_CPU0_SA_DQ<27>
  VSS81  = GND
  \dqs8_a_c||tdqs8_a_c\  = M_H_CPU0_SA_DQS_DN<8>
  \dqs8_a_t||tdqs8_a_t\  = M_H_CPU0_SA_DQS_DP<8>
  VSS82  = GND
  DQ30_A  = M_H_CPU0_SA_DQ<30>
  VSS83  = GND
  DQ31_A  = M_H_CPU0_SA_DQ<31>
  VSS84  = GND
  CB2_A  = M_H_CPU0_SA_CB<2>
  VSS85  = GND
  CB3_A  = M_H_CPU0_SA_CB<3>
  VSS86  = GND
  \dqs9_a_c||tdqs9_a_c\  = M_H_CPU0_SA_DQS_DN<9>
  \dqs9_a_t||tdqs9_a_t\  = M_H_CPU0_SA_DQS_DP<9>
  VSS87  = GND
  CB6_A  = M_H_CPU0_SA_CB<6>
  VSS88  = GND
  CB7_A  = M_H_CPU0_SA_CB<7>
  VSS89  = GND
  RESET_N  = M_H_CPU0_RESET_N
  VSS90  = GND
  CS1_A_N  = M_H_CPU0_SA_CS_N<1>
  VSS91  = GND
  CA1_A  = M_H_CPU0_SA_CA<1>
  VSS92  = GND
  CA3_A  = M_H_CPU0_SA_CA<3>
  VSS93  = GND
  CA5_A  = M_H_CPU0_SA_CA<5>
  VSS94  = GND
  CK_T  = M_H_CPU0_CLK_DP<0>
  CK_C  = M_H_CPU0_CLK_DN<0>
  VSS95  = GND
  RFU4  = NC
  CA1_B  = M_H_CPU0_SB_CA<1>
  VSS96  = GND
  CA3_B  = M_H_CPU0_SB_CA<3>
  VSS97  = GND
  CA5_B  = M_H_CPU0_SB_CA<5>
  VSS98  = GND
  PAR_B  = M_H_CPU0_SB_PAR
  VSS99  = GND
  CS1_B_N  = M_H_CPU0_SB_CS_N<1>
  VSS100  = GND
  RFU5  = NC
  RFU6  = NC
  VSS101  = GND
  CB6_B  = M_H_CPU0_SB_CB<6>
  VSS102  = GND
  CB7_B  = M_H_CPU0_SB_CB<7>
  VSS103  = GND
  DQS4_B_C  = M_H_CPU0_SB_DQS_DN<4>
  DQS4_B_T  = M_H_CPU0_SB_DQS_DP<4>
  VSS104  = GND
  CB2_B  = M_H_CPU0_SB_CB<2>
  VSS105  = GND
  CB3_B  = M_H_CPU0_SB_CB<3>
  VSS106  = GND
  DQ2_B  = M_H_CPU0_SB_DQ<2>
  VSS107  = GND
  DQ3_B  = M_H_CPU0_SB_DQ<3>
  VSS108  = GND
  \dqs5_b_c||tdqs5_b_c\  = M_H_CPU0_SB_DQS_DN<5>
  \dqs5_b_t||tdqs5_b_t\  = M_H_CPU0_SB_DQS_DP<5>
  VSS109  = GND
  DQ6_B  = M_H_CPU0_SB_DQ<6>
  VSS110  = GND
  DQ7_B  = M_H_CPU0_SB_DQ<7>
  VSS111  = GND
  DQ10_B  = M_H_CPU0_SB_DQ<10>
  VSS112  = GND
  DQ11_B  = M_H_CPU0_SB_DQ<11>
  VSS113  = GND
  \dqs6_b_c||tdqs6_b_c\  = M_H_CPU0_SB_DQS_DN<6>
  \dqs6_b_t||tdqs6_b_t\  = M_H_CPU0_SB_DQS_DP<6>
  VSS114  = GND
  DQ14_B  = M_H_CPU0_SB_DQ<14>
  VSS115  = GND
  DQ15_B  = M_H_CPU0_SB_DQ<15>
  VSS116  = GND
  DQ18_B  = M_H_CPU0_SB_DQ<18>
  VSS117  = GND
  DQ19_B  = M_H_CPU0_SB_DQ<19>
  VSS118  = GND
  \dqs7_b_c||tdqs7_b_c\  = M_H_CPU0_SB_DQS_DN<7>
  \dqs7_b_t||tdqs7_b_t\  = M_H_CPU0_SB_DQS_DP<7>
  VSS119  = GND
  DQ22_B  = M_H_CPU0_SB_DQ<22>
  VSS120  = GND
  DQ23_B  = M_H_CPU0_SB_DQ<23>
  VSS121  = GND
  DQ26_B  = M_H_CPU0_SB_DQ<26>
  VSS122  = GND
  DQ27_B  = M_H_CPU0_SB_DQ<27>
  VSS123  = GND
  \dqs8_b_c||tdqs8_b_c\  = M_H_CPU0_SB_DQS_DN<8>
  \dqs8_b_t||tdqs8_b_t\  = M_H_CPU0_SB_DQS_DP<8>
  VSS124  = GND
  DQ30_B  = M_H_CPU0_SB_DQ<30>
  VSS125  = GND
  DQ31_B  = M_H_CPU0_SB_DQ<31>
  VSS126  = GND
  G1  = GND
  G2  = GND
  G3  = GND

(kicad_pcb
	(version 20260206)
	(generator "pcbnew")
	(generator_version "10.0")
	(general
		(thickness 1.6)
		(legacy_teardrops no)
	)
	(paper "A4")
	(title_block
		(title "04192023_DAF0TMB3IC0_F0TG_MB_C_brd_V02_OCP.brd")
		(comment 1 "Grand Teton / footprint 2335 of 8354 (J69), pads 231-276 of 291")
	)
	(layers
		(0 "F.Cu" signal "TOP")
		(4 "In1.Cu" signal "GND")
		(6 "In2.Cu" signal "IN1")
		(8 "In3.Cu" signal "GND1")
		(10 "In4.Cu" signal "IN2")
		(12 "In5.Cu" signal "GND2")
		(14 "In6.Cu" signal "IN3")
		(16 "In7.Cu" signal "GND3")
		(18 "In8.Cu" signal "VCC")
		(20 "In9.Cu" signal "VCC1")
		(22 "In10.Cu" signal "GND4")
		(24 "In11.Cu" signal "IN4")
		(26 "In12.Cu" signal "GND5")
		(28 "In13.Cu" signal "IN5")
		(30 "In14.Cu" signal "GND6")
		(32 "In15.Cu" signal "IN6")
		(34 "In16.Cu" signal "GND7")
		(2 "B.Cu" signal "BOTTOM")
		(9 "F.Adhes" user "F.Adhesive")
		(11 "B.Adhes" user "B.Adhesive")
		(13 "F.Paste" user "Package Geometry/Pastemask Top")
		(15 "B.Paste" user "Package Geometry/Pastemask Bottom")
		(5 "F.SilkS" user "Ref Des/Silkscreen Top")
		(7 "B.SilkS" user "Ref Des/Silkscreen Bottom")
		(1 "F.Mask" user "Board Geometry/Soldermask Top")
		(3 "B.Mask" user "Board Geometry/Soldermask Bottom")
		(17 "Dwgs.User" user "User.Drawings")
		(19 "Cmts.User" user "User.Comments")
		(21 "Eco1.User" user "User.Eco1")
		(23 "Eco2.User" user "User.Eco2")
		(25 "Edge.Cuts" user "Board Geometry/Outline")
		(27 "Margin" user)
		(31 "F.CrtYd" user "Package Geometry/Place Bound Top")
		(29 "B.CrtYd" user "Package Geometry/Place Bound Bottom")
		(35 "F.Fab" user "Ref Des/Assembly Top")
		(33 "B.Fab" user "Ref Des/Assembly Bottom")
	)
	(footprint ""
		(layer "F.Cu")
		(at 421.962072 -255.560068 180)
		(property "Reference" "J69"
			(at 3.448304 81.947512 0)
			(unlocked yes)
			(layer "F.SilkS")
			(effects
				(font
					(size 0.7874 0.5842)
					(thickness 0.1524)
				)
			)
		)
		(property "Value" ""
			(at 0 0 180)
			(layer "F.Fab")
			(effects
				(font
					(size 1.27 1.27)
				)
			)
		)
		(duplicate_pad_numbers_are_jumpers no)
		(pad "231" smd rect
			(at 2.050034 14.875002 90)
			(size 0.519938 1.4986)
			(layers "F.Cu" "F.Mask" "F.Paste")
			(net "Net_2352")
		)
		(pad "232" smd rect
			(at 2.050034 15.724886 90)
			(size 0.519938 1.4986)
			(layers "F.Cu" "F.Mask" "F.Paste")
			(net "Net_2353")
		)
		(pad "233" smd rect
			(at 2.050034 16.575024 90)
			(size 0.519938 1.4986)
			(layers "F.Cu" "F.Mask" "F.Paste")
			(net "GND")
		)
		(pad "234" smd rect
			(at 2.050034 17.424908 90)
			(size 0.519938 1.4986)
			(layers "F.Cu" "F.Mask" "F.Paste")
			(net "M_H_CPU0_SB_CB<6>")
		)
		(pad "235" smd rect
			(at 2.050034 18.275046 90)
			(size 0.519938 1.4986)
			(layers "F.Cu" "F.Mask" "F.Paste")
			(net "GND")
		)
		(pad "236" smd rect
			(at 2.050034 19.12493 90)
			(size 0.519938 1.4986)
			(layers "F.Cu" "F.Mask" "F.Paste")
			(net "M_H_CPU0_SB_CB<7>")
		)
		(pad "237" smd rect
			(at 2.050034 19.975068 90)
			(size 0.519938 1.4986)
			(layers "F.Cu" "F.Mask" "F.Paste")
			(net "GND")
		)
		(pad "238" smd rect
			(at 2.050034 20.824952 90)
			(size 0.519938 1.4986)
			(layers "F.Cu" "F.Mask" "F.Paste")
			(net "M_H_CPU0_SB_DQS_DN<4>")
		)
		(pad "239" smd rect
			(at 2.050034 21.67509 90)
			(size 0.519938 1.4986)
			(layers "F.Cu" "F.Mask" "F.Paste")
			(net "M_H_CPU0_SB_DQS_DP<4>")
		)
		(pad "240" smd rect
			(at 2.050034 22.524974 90)
			(size 0.519938 1.4986)
			(layers "F.Cu" "F.Mask" "F.Paste")
			(net "GND")
		)
		(pad "241" smd rect
			(at 2.050034 23.375112 90)
			(size 0.519938 1.4986)
			(layers "F.Cu" "F.Mask" "F.Paste")
			(net "M_H_CPU0_SB_CB<2>")
		)
		(pad "242" smd rect
			(at 2.050034 24.224996 90)
			(size 0.519938 1.4986)
			(layers "F.Cu" "F.Mask" "F.Paste")
			(net "GND")
		)
		(pad "243" smd rect
			(at 2.050034 25.07488 90)
			(size 0.519938 1.4986)
			(layers "F.Cu" "F.Mask" "F.Paste")
			(net "M_H_CPU0_SB_CB<3>")
		)
		(pad "244" smd rect
			(at 2.050034 25.925018 90)
			(size 0.519938 1.4986)
			(layers "F.Cu" "F.Mask" "F.Paste")
			(net "GND")
		)
		(pad "245" smd rect
			(at 2.050034 26.774902 90)
			(size 0.519938 1.4986)
			(layers "F.Cu" "F.Mask" "F.Paste")
			(net "M_H_CPU0_SB_DQ<2>")
		)
		(pad "246" smd rect
			(at 2.050034 27.62504 90)
			(size 0.519938 1.4986)
			(layers "F.Cu" "F.Mask" "F.Paste")
			(net "GND")
		)
		(pad "247" smd rect
			(at 2.050034 28.474924 90)
			(size 0.519938 1.4986)
			(layers "F.Cu" "F.Mask" "F.Paste")
			(net "M_H_CPU0_SB_DQ<3>")
		)
		(pad "248" smd rect
			(at 2.050034 29.325062 90)
			(size 0.519938 1.4986)
			(layers "F.Cu" "F.Mask" "F.Paste")
			(net "GND")
		)
		(pad "249" smd rect
			(at 2.050034 30.174946 90)
			(size 0.519938 1.4986)
			(layers "F.Cu" "F.Mask" "F.Paste")
			(net "M_H_CPU0_SB_DQS_DN<5>")
		)
		(pad "250" smd rect
			(at 2.050034 31.025084 90)
			(size 0.519938 1.4986)
			(layers "F.Cu" "F.Mask" "F.Paste")
			(net "M_H_CPU0_SB_DQS_DP<5>")
		)
		(pad "251" smd rect
			(at 2.050034 31.874968 90)
			(size 0.519938 1.4986)
			(layers "F.Cu" "F.Mask" "F.Paste")
			(net "GND")
		)
		(pad "252" smd rect
			(at 2.050034 32.725106 90)
			(size 0.519938 1.4986)
			(layers "F.Cu" "F.Mask" "F.Paste")
			(net "M_H_CPU0_SB_DQ<6>")
		)
		(pad "253" smd rect
			(at 2.050034 33.57499 90)
			(size 0.519938 1.4986)
			(layers "F.Cu" "F.Mask" "F.Paste")
			(net "GND")
		)
		(pad "254" smd rect
			(at 2.050034 34.425128 90)
			(size 0.519938 1.4986)
			(layers "F.Cu" "F.Mask" "F.Paste")
			(net "M_H_CPU0_SB_DQ<7>")
		)
		(pad "255" smd rect
			(at 2.050034 35.275012 90)
			(size 0.519938 1.4986)
			(layers "F.Cu" "F.Mask" "F.Paste")
			(net "GND")
		)
		(pad "256" smd rect
			(at 2.050034 36.124896 90)
			(size 0.519938 1.4986)
			(layers "F.Cu" "F.Mask" "F.Paste")
			(net "M_H_CPU0_SB_DQ<10>")
		)
		(pad "257" smd rect
			(at 2.050034 36.975034 90)
			(size 0.519938 1.4986)
			(layers "F.Cu" "F.Mask" "F.Paste")
			(net "GND")
		)
		(pad "258" smd rect
			(at 2.050034 37.824918 90)
			(size 0.519938 1.4986)
			(layers "F.Cu" "F.Mask" "F.Paste")
			(net "M_H_CPU0_SB_DQ<11>")
		)
		(pad "259" smd rect
			(at 2.050034 38.675056 90)
			(size 0.519938 1.4986)
			(layers "F.Cu" "F.Mask" "F.Paste")
			(net "GND")
		)
		(pad "260" smd rect
			(at 2.050034 39.52494 90)
			(size 0.519938 1.4986)
			(layers "F.Cu" "F.Mask" "F.Paste")
			(net "M_H_CPU0_SB_DQS_DN<6>")
		)
		(pad "261" smd rect
			(at 2.050034 40.375078 90)
			(size 0.519938 1.4986)
			(layers "F.Cu" "F.Mask" "F.Paste")
			(net "M_H_CPU0_SB_DQS_DP<6>")
		)
		(pad "262" smd rect
			(at 2.050034 41.224962 90)
			(size 0.519938 1.4986)
			(layers "F.Cu" "F.Mask" "F.Paste")
			(net "GND")
		)
		(pad "263" smd rect
			(at 2.050034 42.0751 90)
			(size 0.519938 1.4986)
			(layers "F.Cu" "F.Mask" "F.Paste")
			(net "M_H_CPU0_SB_DQ<14>")
		)
		(pad "264" smd rect
			(at 2.050034 42.924984 90)
			(size 0.519938 1.4986)
			(layers "F.Cu" "F.Mask" "F.Paste")
			(net "GND")
		)
		(pad "265" smd rect
			(at 2.050034 43.775122 90)
			(size 0.519938 1.4986)
			(layers "F.Cu" "F.Mask" "F.Paste")
			(net "M_H_CPU0_SB_DQ<15>")
		)
		(pad "266" smd rect
			(at 2.050034 44.625006 90)
			(size 0.519938 1.4986)
			(layers "F.Cu" "F.Mask" "F.Paste")
			(net "GND")
		)
		(pad "267" smd rect
			(at 2.050034 45.47489 90)
			(size 0.519938 1.4986)
			(layers "F.Cu" "F.Mask" "F.Paste")
			(net "M_H_CPU0_SB_DQ<18>")
		)
		(pad "268" smd rect
			(at 2.050034 46.325028 90)
			(size 0.519938 1.4986)
			(layers "F.Cu" "F.Mask" "F.Paste")
			(net "GND")
		)
		(pad "269" smd rect
			(at 2.050034 47.174912 90)
			(size 0.519938 1.4986)
			(layers "F.Cu" "F.Mask" "F.Paste")
			(net "M_H_CPU0_SB_DQ<19>")
		)
		(pad "270" smd rect
			(at 2.050034 48.02505 90)
			(size 0.519938 1.4986)
			(layers "F.Cu" "F.Mask" "F.Paste")
			(net "GND")
		)
		(pad "271" smd rect
			(at 2.050034 48.874934 90)
			(size 0.519938 1.4986)
			(layers "F.Cu" "F.Mask" "F.Paste")
			(net "M_H_CPU0_SB_DQS_DN<7>")
		)
		(pad "272" smd rect
			(at 2.050034 49.725072 90)
			(size 0.519938 1.4986)
			(layers "F.Cu" "F.Mask" "F.Paste")
			(net "M_H_CPU0_SB_DQS_DP<7>")
		)
		(pad "273" smd rect
			(at 2.050034 50.574956 90)
			(size 0.519938 1.4986)
			(layers "F.Cu" "F.Mask" "F.Paste")
			(net "GND")
		)
		(pad "274" smd rect
			(at 2.050034 51.425094 90)
			(size 0.519938 1.4986)
			(layers "F.Cu" "F.Mask" "F.Paste")
			(net "M_H_CPU0_SB_DQ<22>")
		)
		(pad "275" smd rect
			(at 2.050034 52.274978 90)
			(size 0.519938 1.4986)
			(layers "F.Cu" "F.Mask" "F.Paste")
			(net "GND")
		)
		(pad "276" smd rect
			(at 2.050034 53.125116 90)
			(size 0.519938 1.4986)
			(layers "F.Cu" "F.Mask" "F.Paste")
			(net "M_H_CPU0_SB_DQ<23>")
		)
	)
)
